# S9S_MB_2U (Grand Teton) — schematic netlist excerpt (pin names and nets, part order shuffled) for the footprints in the layout excerpt that follows; sources: Cadence DE-HDL packaged netlist, KiCad conversion of 03242023_DA0F0TMBIJ0_F0T_Motherboard_J_brd_V01_OCP.brd

J16  SCONN288_ADR50017P087CC  SCONN288_ADR50017-P087CC IO  pkg DDR288S_1-1VXB  page 97
  VIN_BULK0  = P12V_S3_AUX_CPU0_NVDIMM
  RFU0  = TP_CHH_CPU0_DIMM2_FRU_0
  VIN_MGMT  = P3V3_AUX
  HSCL  = I3C_SPD_DDREFGH_CPU0_LVC1_SCL_7
  HSDA  = I3C_SPD_DDREFGH_CPU0_LVC1_SDA
  VSS0  = GND
  DQ0_A  = M_H_CPU0_SA_DQ<0>
  VSS1  = GND
  DQ1_A  = M_H_CPU0_SA_DQ<1>
  VSS2  = GND
  DQS0_A_T  = M_H_CPU0_SA_DQS_DP<0>
  DQS0_A_C  = M_H_CPU0_SA_DQS_DN<0>
  VSS3  = GND
  DQ4_A  = M_H_CPU0_SA_DQ<4>
  VSS4  = GND
  DQ5_A  = M_H_CPU0_SA_DQ<5>
  VSS5  = GND
  DQ8_A  = M_H_CPU0_SA_DQ<8>
  VSS6  = GND
  DQ9_A  = M_H_CPU0_SA_DQ<9>
  VSS7  = GND
  DQS1_A_T  = M_H_CPU0_SA_DQS_DP<1>
  DQS1_A_C  = M_H_CPU0_SA_DQS_DN<1>
  VSS8  = GND
  DQ12_A  = M_H_CPU0_SA_DQ<12>
  VSS9  = GND
  DQ13_A  = M_H_CPU0_SA_DQ<13>
  VSS10  = GND
  DQ16_A  = M_H_CPU0_SA_DQ<16>
  VSS11  = GND
  DQ17_A  = M_H_CPU0_SA_DQ<17>
  VSS12  = GND
  DQS2_A_T  = M_H_CPU0_SA_DQS_DP<2>
  DQS2_A_C  = M_H_CPU0_SA_DQS_DN<2>
  VSS13  = GND
  DQ20_A  = M_H_CPU0_SA_DQ<20>
  VSS14  = GND
  DQ21_A  = M_H_CPU0_SA_DQ<21>
  VSS15  = GND
  DQ24_A  = M_H_CPU0_SA_DQ<24>
  VSS16  = GND
  DQ25_A  = M_H_CPU0_SA_DQ<25>
  VSS17  = GND
  DQS3_A_T  = M_H_CPU0_SA_DQS_DP<3>
  DQS3_A_C  = M_H_CPU0_SA_DQS_DN<3>
  VSS18  = GND
  DQ28_A  = M_H_CPU0_SA_DQ<28>
  VSS19  = GND
  DQ29_A  = M_H_CPU0_SA_DQ<29>
  VSS20  = GND
  CB0_A  = M_H_CPU0_SA_CB<0>
  VSS21  = GND
  CB1_A  = M_H_CPU0_SA_CB<1>
  VSS22  = GND
  DQS4_A_T  = M_H_CPU0_SA_DQS_DP<4>
  DQS4_A_C  = M_H_CPU0_SA_DQS_DN<4>
  VSS23  = GND
  CB4_A  = M_H_CPU0_SA_CB<4>
  VSS24  = GND
  CB5_A  = M_H_CPU0_SA_CB<5>
  VSS25  = GND
  ALERT_N  = M_H_CPU0_ALERT_N
  VSS26  = GND
  CS0_A_N  = M_H_CPU0_SA_CS_N<2>
  VSS27  = GND
  CA0_A  = M_H_CPU0_SA_CA<0>
  VSS28  = GND
  CA2_A  = M_H_CPU0_SA_CA<2>
  VSS29  = GND
  CA4_A  = M_H_CPU0_SA_CA<4>
  VSS30  = GND
  CA6_A  = M_H_CPU0_SA_CA<6>
  VSS31  = GND
  PAR_A  = M_H_CPU0_SA_PAR
  VSS32  = GND
  CA0_B  = M_H_CPU0_SB_CA<0>
  VSS33  = GND
  CA2_B  = M_H_CPU0_SB_CA<2>
  VSS34  = GND
  CA4_B  = M_H_CPU0_SB_CA<4>
  VSS35  = GND
  CA6_B  = M_H_CPU0_SB_CA<6>
  VSS36  = GND
  CS0_B_N  = M_H_CPU0_SB_CS_N<2>
  VSS37  = GND
  \lbd||rsp_a_n\  = M_H_CPU0_SA_RSP<1>
  \lbs||rsp_b_n\  = M_H_CPU0_SB_RSP<1>
  VSS38  = GND
  CB4_B  = M_H_CPU0_SB_CB<4>
  VSS39  = GND
  CB5_B  = M_H_CPU0_SB_CB<5>
  VSS40  = GND
  \dqs9_b_t||tdqs9_b_t||dbi4_b_n\  = M_H_CPU0_SB_DQS_DP<9>
  \dqs9_b_c||tdqs9_b_c\  = M_H_CPU0_SB_DQS_DN<9>
  VSS41  = GND
  CB0_B  = M_H_CPU0_SB_CB<0>
  VSS42  = GND
  CB1_B  = M_H_CPU0_SB_CB<1>
  VSS43  = GND
  DQ0_B  = M_H_CPU0_SB_DQ<0>
  VSS44  = GND
  DQ1_B  = M_H_CPU0_SB_DQ<1>
  VSS45  = GND
  DQS0_B_T  = M_H_CPU0_SB_DQS_DP<0>
  DQS0_B_C  = M_H_CPU0_SB_DQS_DN<0>
  VSS46  = GND
  DQ4_B  = M_H_CPU0_SB_DQ<4>
  VSS47  = GND
  DQ5_B  = M_H_CPU0_SB_DQ<5>
  VSS48  = GND
  DQ8_B  = M_H_CPU0_SB_DQ<8>
  VSS49  = GND
  DQ9_B  = M_H_CPU0_SB_DQ<9>
  VSS50  = GND
  DQS1_B_T  = M_H_CPU0_SB_DQS_DP<1>
  DQS1_B_C  = M_H_CPU0_SB_DQS_DN<1>
  VSS51  = GND
  DQ12_B  = M_H_CPU0_SB_DQ<12>
  VSS52  = GND
  DQ13_B  = M_H_CPU0_SB_DQ<13>
  VSS53  = GND
  DQ16_B  = M_H_CPU0_SB_DQ<16>
  VSS54  = GND
  DQ17_B  = M_H_CPU0_SB_DQ<17>
  VSS55  = GND
  DQS2_B_T  = M_H_CPU0_SB_DQS_DP<2>
  DQS2_B_C  = M_H_CPU0_SB_DQS_DN<2>
  VSS56  = GND
  DQ20_B  = M_H_CPU0_SB_DQ<20>
  VSS57  = GND
  DQ21_B  = M_H_CPU0_SB_DQ<21>
  VSS58  = GND
  DQ24_B  = M_H_CPU0_SB_DQ<24>
  VSS59  = GND
  DQ25_B  = M_H_CPU0_SB_DQ<25>
  VSS60  = GND
  DQS3_B_T  = M_H_CPU0_SB_DQS_DP<3>
  DQS3_B_C  = M_H_CPU0_SB_DQS_DN<3>
  VSS61  = GND
  DQ28_B  = M_H_CPU0_SB_DQ<28>
  VSS62  = GND
  DQ29_B  = M_H_CPU0_SB_DQ<29>
  VSS63  = GND
  RFU1  = TP_CHH_CPU0_DIMM2_FRU_1
  VIN_BULK1  = P12V_S3_AUX_CPU0_NVDIMM
  VIN_BULK2  = P12V_S3_AUX_CPU0_NVDIMM
  \pwr_good||fail_n\  = PWRGD_CHH_CPU0_DIMM2
  HSA  = PD_CHH_CPU0_DIMM2_SAA
  RFU2  = TP_CHH_CPU0_DIMM2_FRU_2
  RFU3  = TP_CHH_CPU0_DIMM2_FRU_3
  VSS64  = GND
  DQ2_A  = M_H_CPU0_SA_DQ<2>
  VSS65  = GND
  DQ3_A  = M_H_CPU0_SA_DQ<3>
  VSS66  = GND
  \dqs5_a_c||tdqs5_a_c||dqs5_a_t||tdqs5_a_t\  = M_H_CPU0_SA_DQS_DN<5>
  \dqs5_a_t||tdqs5_a_t\  = M_H_CPU0_SA_DQS_DP<5>
  VSS67  = GND
  DQ6_A  = M_H_CPU0_SA_DQ<6>
  VSS68  = GND
  DQ7_A  = M_H_CPU0_SA_DQ<7>
  VSS69  = GND
  DQ10_A  = M_H_CPU0_SA_DQ<10>
  VSS70  = GND
  DQ11_A  = M_H_CPU0_SA_DQ<11>
  VSS71  = GND
  \dqs6_a_c||tdqs6_a_c||dqs6_a_t||tdqs6_a_t\  = M_H_CPU0_SA_DQS_DN<6>
  \dqs6_a_t||tdqs6_a_t\  = M_H_CPU0_SA_DQS_DP<6>
  VSS72  = GND
  DQ14_A  = M_H_CPU0_SA_DQ<14>
  VSS73  = GND
  DQ15_A  = M_H_CPU0_SA_DQ<15>
  VSS74  = GND
  DQ18_A  = M_H_CPU0_SA_DQ<18>
  VSS75  = GND
  DQ19_A  = M_H_CPU0_SA_DQ<19>
  VSS76  = GND
  \dqs7_a_c||tdqs7_a_c\  = M_H_CPU0_SA_DQS_DN<7>
  \dqs7_a_t||tdqs7_a_t\  = M_H_CPU0_SA_DQS_DP<7>
  VSS77  = GND
  DQ22_A  = M_H_CPU0_SA_DQ<22>
  VSS78  = GND
  DQ23_A  = M_H_CPU0_SA_DQ<23>
  VSS79  = GND
  DQ26_A  = M_H_CPU0_SA_DQ<26>
  VSS80  = GND
  DQ27_A  = M_H_CPU0_SA_DQ<27>
  VSS81  = GND
  \dqs8_a_c||tdqs8_a_c\  = M_H_CPU0_SA_DQS_DN<8>
  \dqs8_a_t||tdqs8_a_t\  = M_H_CPU0_SA_DQS_DP<8>
  VSS82  = GND
  DQ30_A  = M_H_CPU0_SA_DQ<30>
  VSS83  = GND
  DQ31_A  = M_H_CPU0_SA_DQ<31>
  VSS84  = GND
  CB2_A  = M_H_CPU0_SA_CB<2>
  VSS85  = GND
  CB3_A  = M_H_CPU0_SA_CB<3>
  VSS86  = GND
  \dqs9_a_c||tdqs9_a_c\  = M_H_CPU0_SA_DQS_DN<9>
  \dqs9_a_t||tdqs9_a_t\  = M_H_CPU0_SA_DQS_DP<9>
  VSS87  = GND
  CB6_A  = M_H_CPU0_SA_CB<6>
  VSS88  = GND
  CB7_A  = M_H_CPU0_SA_CB<7>
  VSS89  = GND
  RESET_N  = RST_M_GH_CPU0_FPGA_N
  VSS90  = GND
  CS1_A_N  = M_H_CPU0_SA_CS_N<3>
  VSS91  = GND
  CA1_A  = M_H_CPU0_SA_CA<1>
  VSS92  = GND
  CA3_A  = M_H_CPU0_SA_CA<3>
  VSS93  = GND
  CA5_A  = M_H_CPU0_SA_CA<5>
  VSS94  = GND
  CK_T  = M_H_CPU0_CLK_DP<1>
  CK_C  = M_H_CPU0_CLK_DN<1>
  VSS95  = GND
  RFU4  = TP_CHH_CPU0_DIMM2_FRU_4
  CA1_B  = M_H_CPU0_SB_CA<1>
  VSS96  = GND
  CA3_B  = M_H_CPU0_SB_CA<3>
  VSS97  = GND
  CA5_B  = M_H_CPU0_SB_CA<5>
  VSS98  = GND
  PAR_B  = M_H_CPU0_SB_PAR
  VSS99  = GND
  CS1_B_N  = M_H_CPU0_SB_CS_N<3>
  VSS100  = GND
  RFU5  = TP_CHH_CPU0_DIMM2_FRU_5
  RFU6  = TP_CHH_CPU0_DIMM2_FRU_6
  VSS101  = GND
  CB6_B  = M_H_CPU0_SB_CB<6>
  VSS102  = GND
  CB7_B  = M_H_CPU0_SB_CB<7>
  VSS103  = GND
  DQS4_B_C  = M_H_CPU0_SB_DQS_DN<4>
  DQS4_B_T  = M_H_CPU0_SB_DQS_DP<4>
  VSS104  = GND
  CB2_B  = M_H_CPU0_SB_CB<2>
  VSS105  = GND
  CB3_B  = M_H_CPU0_SB_CB<3>
  VSS106  = GND
  DQ2_B  = M_H_CPU0_SB_DQ<2>
  VSS107  = GND
  DQ3_B  = M_H_CPU0_SB_DQ<3>
  VSS108  = GND
  \dqs5_b_c||tdqs5_b_c\  = M_H_CPU0_SB_DQS_DN<5>
  \dqs5_b_t||tdqs5_b_t\  = M_H_CPU0_SB_DQS_DP<5>
  VSS109  = GND
  DQ6_B  = M_H_CPU0_SB_DQ<6>
  VSS110  = GND
  DQ7_B  = M_H_CPU0_SB_DQ<7>
  VSS111  = GND
  DQ10_B  = M_H_CPU0_SB_DQ<10>
  VSS112  = GND
  DQ11_B  = M_H_CPU0_SB_DQ<11>
  VSS113  = GND
  \dqs6_b_c||tdqs6_b_c\  = M_H_CPU0_SB_DQS_DN<6>
  \dqs6_b_t||tdqs6_b_t\  = M_H_CPU0_SB_DQS_DP<6>
  VSS114  = GND
  DQ14_B  = M_H_CPU0_SB_DQ<14>
  VSS115  = GND
  DQ15_B  = M_H_CPU0_SB_DQ<15>
  VSS116  = GND
  DQ18_B  = M_H_CPU0_SB_DQ<18>
  VSS117  = GND
  DQ19_B  = M_H_CPU0_SB_DQ<19>
  VSS118  = GND
  \dqs7_b_c||tdqs7_b_c\  = M_H_CPU0_SB_DQS_DN<7>
  \dqs7_b_t||tdqs7_b_t\  = M_H_CPU0_SB_DQS_DP<7>
  VSS119  = GND
  DQ22_B  = M_H_CPU0_SB_DQ<22>
  VSS120  = GND
  DQ23_B  = M_H_CPU0_SB_DQ<23>
  VSS121  = GND
  DQ26_B  = M_H_CPU0_SB_DQ<26>
  VSS122  = GND
  DQ27_B  = M_H_CPU0_SB_DQ<27>
  VSS123  = GND
  \dqs8_b_c||tdqs8_b_c\  = M_H_CPU0_SB_DQS_DN<8>
  \dqs8_b_t||tdqs8_b_t\  = M_H_CPU0_SB_DQS_DP<8>
  VSS124  = GND
  DQ30_B  = M_H_CPU0_SB_DQ<30>
  VSS125  = GND
  DQ31_B  = M_H_CPU0_SB_DQ<31>
  VSS126  = GND
  G1  = GND
  G2  = GND
  G3  = GND

(kicad_pcb
	(version 20260206)
	(generator "pcbnew")
	(generator_version "10.0")
	(general
		(thickness 1.6)
		(legacy_teardrops no)
	)
	(paper "A4")
	(title_block
		(title "03242023_DA0F0TMBIJ0_F0T_Motherboard_J_brd_V01_OCP.brd")
		(comment 1 "Grand Teton / footprint 1690 of 6105 (J16), pads 92-137 of 291")
	)
	(layers
		(0 "F.Cu" signal "TOP")
		(4 "In1.Cu" signal "GND")
		(6 "In2.Cu" signal "IN1")
		(8 "In3.Cu" signal "GND1")
		(10 "In4.Cu" signal "IN2")
		(12 "In5.Cu" signal "GND2")
		(14 "In6.Cu" signal "IN3")
		(16 "In7.Cu" signal "GND3")
		(18 "In8.Cu" signal "VCC")
		(20 "In9.Cu" signal "VCC1")
		(22 "In10.Cu" signal "GND4")
		(24 "In11.Cu" signal "IN4")
		(26 "In12.Cu" signal "GND5")
		(28 "In13.Cu" signal "IN5")
		(30 "In14.Cu" signal "GND6")
		(32 "In15.Cu" signal "IN6")
		(34 "In16.Cu" signal "GND7")
		(2 "B.Cu" signal "BOTTOM")
		(9 "F.Adhes" user "F.Adhesive")
		(11 "B.Adhes" user "B.Adhesive")
		(13 "F.Paste" user "Package Geometry/Pastemask Top")
		(15 "B.Paste" user "Package Geometry/Pastemask Bottom")
		(5 "F.SilkS" user "Ref Des/Silkscreen Top")
		(7 "B.SilkS" user "Ref Des/Silkscreen Bottom")
		(1 "F.Mask" user "Board Geometry/Soldermask Top")
		(3 "B.Mask" user "Board Geometry/Soldermask Bottom")
		(17 "Dwgs.User" user "User.Drawings")
		(19 "Cmts.User" user "User.Comments")
		(21 "Eco1.User" user "User.Eco1")
		(23 "Eco2.User" user "User.Eco2")
		(25 "Edge.Cuts" user "Board Geometry/Outline")
		(27 "Margin" user)
		(31 "F.CrtYd" user "Package Geometry/Place Bound Top")
		(29 "B.CrtYd" user "Package Geometry/Place Bound Bottom")
		(35 "F.Fab" user "Ref Des/Assembly Top")
		(33 "B.Fab" user "Ref Des/Assembly Bottom")
	)
	(footprint ""
		(layer "F.Cu")
		(at 454.066148 -258.091686)
		(property "Reference" "J16"
			(at -0.279908 -81.779872 0)
			(unlocked yes)
			(layer "F.SilkS")
			(effects
				(font
					(size 0.7874 0.5842)
					(thickness 0.1524)
				)
				(justify left)
			)
		)
		(property "Value" ""
			(at 0 0 0)
			(layer "F.Fab")
			(effects
				(font
					(size 1.27 1.27)
				)
			)
		)
		(duplicate_pad_numbers_are_jumpers no)
		(pad "92" smd rect
			(at -2.050034 19.12493 270)
			(size 0.519938 1.4986)
			(layers "F.Cu" "F.Mask" "F.Paste")
			(net "GND")
		)
		(pad "93" smd rect
			(at -2.050034 19.975068 270)
			(size 0.519938 1.4986)
			(layers "F.Cu" "F.Mask" "F.Paste")
			(net "M_H_CPU0_SB_DQS_DP<9>")
		)
		(pad "94" smd rect
			(at -2.050034 20.824952 270)
			(size 0.519938 1.4986)
			(layers "F.Cu" "F.Mask" "F.Paste")
			(net "M_H_CPU0_SB_DQS_DN<9>")
		)
		(pad "95" smd rect
			(at -2.050034 21.67509 270)
			(size 0.519938 1.4986)
			(layers "F.Cu" "F.Mask" "F.Paste")
			(net "GND")
		)
		(pad "96" smd rect
			(at -2.050034 22.524974 270)
			(size 0.519938 1.4986)
			(layers "F.Cu" "F.Mask" "F.Paste")
			(net "M_H_CPU0_SB_CB<0>")
		)
		(pad "97" smd rect
			(at -2.050034 23.375112 270)
			(size 0.519938 1.4986)
			(layers "F.Cu" "F.Mask" "F.Paste")
			(net "GND")
		)
		(pad "98" smd rect
			(at -2.050034 24.224996 270)
			(size 0.519938 1.4986)
			(layers "F.Cu" "F.Mask" "F.Paste")
			(net "M_H_CPU0_SB_CB<1>")
		)
		(pad "99" smd rect
			(at -2.050034 25.07488 270)
			(size 0.519938 1.4986)
			(layers "F.Cu" "F.Mask" "F.Paste")
			(net "GND")
		)
		(pad "100" smd rect
			(at -2.050034 25.925018 270)
			(size 0.519938 1.4986)
			(layers "F.Cu" "F.Mask" "F.Paste")
			(net "M_H_CPU0_SB_DQ<0>")
		)
		(pad "101" smd rect
			(at -2.050034 26.774902 270)
			(size 0.519938 1.4986)
			(layers "F.Cu" "F.Mask" "F.Paste")
			(net "GND")
		)
		(pad "102" smd rect
			(at -2.050034 27.62504 270)
			(size 0.519938 1.4986)
			(layers "F.Cu" "F.Mask" "F.Paste")
			(net "M_H_CPU0_SB_DQ<1>")
		)
		(pad "103" smd rect
			(at -2.050034 28.474924 270)
			(size 0.519938 1.4986)
			(layers "F.Cu" "F.Mask" "F.Paste")
			(net "GND")
		)
		(pad "104" smd rect
			(at -2.050034 29.325062 270)
			(size 0.519938 1.4986)
			(layers "F.Cu" "F.Mask" "F.Paste")
			(net "M_H_CPU0_SB_DQS_DP<0>")
		)
		(pad "105" smd rect
			(at -2.050034 30.174946 270)
			(size 0.519938 1.4986)
			(layers "F.Cu" "F.Mask" "F.Paste")
			(net "M_H_CPU0_SB_DQS_DN<0>")
		)
		(pad "106" smd rect
			(at -2.050034 31.025084 270)
			(size 0.519938 1.4986)
			(layers "F.Cu" "F.Mask" "F.Paste")
			(net "GND")
		)
		(pad "107" smd rect
			(at -2.050034 31.874968 270)
			(size 0.519938 1.4986)
			(layers "F.Cu" "F.Mask" "F.Paste")
			(net "M_H_CPU0_SB_DQ<4>")
		)
		(pad "108" smd rect
			(at -2.050034 32.725106 270)
			(size 0.519938 1.4986)
			(layers "F.Cu" "F.Mask" "F.Paste")
			(net "GND")
		)
		(pad "109" smd rect
			(at -2.050034 33.57499 270)
			(size 0.519938 1.4986)
			(layers "F.Cu" "F.Mask" "F.Paste")
			(net "M_H_CPU0_SB_DQ<5>")
		)
		(pad "110" smd rect
			(at -2.050034 34.425128 270)
			(size 0.519938 1.4986)
			(layers "F.Cu" "F.Mask" "F.Paste")
			(net "GND")
		)
		(pad "111" smd rect
			(at -2.050034 35.275012 270)
			(size 0.519938 1.4986)
			(layers "F.Cu" "F.Mask" "F.Paste")
			(net "M_H_CPU0_SB_DQ<8>")
		)
		(pad "112" smd rect
			(at -2.050034 36.124896 270)
			(size 0.519938 1.4986)
			(layers "F.Cu" "F.Mask" "F.Paste")
			(net "GND")
		)
		(pad "113" smd rect
			(at -2.050034 36.975034 270)
			(size 0.519938 1.4986)
			(layers "F.Cu" "F.Mask" "F.Paste")
			(net "M_H_CPU0_SB_DQ<9>")
		)
		(pad "114" smd rect
			(at -2.050034 37.824918 270)
			(size 0.519938 1.4986)
			(layers "F.Cu" "F.Mask" "F.Paste")
			(net "GND")
		)
		(pad "115" smd rect
			(at -2.050034 38.675056 270)
			(size 0.519938 1.4986)
			(layers "F.Cu" "F.Mask" "F.Paste")
			(net "M_H_CPU0_SB_DQS_DP<1>")
		)
		(pad "116" smd rect
			(at -2.050034 39.52494 270)
			(size 0.519938 1.4986)
			(layers "F.Cu" "F.Mask" "F.Paste")
			(net "M_H_CPU0_SB_DQS_DN<1>")
		)
		(pad "117" smd rect
			(at -2.050034 40.375078 270)
			(size 0.519938 1.4986)
			(layers "F.Cu" "F.Mask" "F.Paste")
			(net "GND")
		)
		(pad "118" smd rect
			(at -2.050034 41.224962 270)
			(size 0.519938 1.4986)
			(layers "F.Cu" "F.Mask" "F.Paste")
			(net "M_H_CPU0_SB_DQ<12>")
		)
		(pad "119" smd rect
			(at -2.050034 42.0751 270)
			(size 0.519938 1.4986)
			(layers "F.Cu" "F.Mask" "F.Paste")
			(net "GND")
		)
		(pad "120" smd rect
			(at -2.050034 42.924984 270)
			(size 0.519938 1.4986)
			(layers "F.Cu" "F.Mask" "F.Paste")
			(net "M_H_CPU0_SB_DQ<13>")
		)
		(pad "121" smd rect
			(at -2.050034 43.775122 270)
			(size 0.519938 1.4986)
			(layers "F.Cu" "F.Mask" "F.Paste")
			(net "GND")
		)
		(pad "122" smd rect
			(at -2.050034 44.625006 270)
			(size 0.519938 1.4986)
			(layers "F.Cu" "F.Mask" "F.Paste")
			(net "M_H_CPU0_SB_DQ<16>")
		)
		(pad "123" smd rect
			(at -2.050034 45.47489 270)
			(size 0.519938 1.4986)
			(layers "F.Cu" "F.Mask" "F.Paste")
			(net "GND")
		)
		(pad "124" smd rect
			(at -2.050034 46.325028 270)
			(size 0.519938 1.4986)
			(layers "F.Cu" "F.Mask" "F.Paste")
			(net "M_H_CPU0_SB_DQ<17>")
		)
		(pad "125" smd rect
			(at -2.050034 47.174912 270)
			(size 0.519938 1.4986)
			(layers "F.Cu" "F.Mask" "F.Paste")
			(net "GND")
		)
		(pad "126" smd rect
			(at -2.050034 48.02505 270)
			(size 0.519938 1.4986)
			(layers "F.Cu" "F.Mask" "F.Paste")
			(net "M_H_CPU0_SB_DQS_DP<2>")
		)
		(pad "127" smd rect
			(at -2.050034 48.874934 270)
			(size 0.519938 1.4986)
			(layers "F.Cu" "F.Mask" "F.Paste")
			(net "M_H_CPU0_SB_DQS_DN<2>")
		)
		(pad "128" smd rect
			(at -2.050034 49.725072 270)
			(size 0.519938 1.4986)
			(layers "F.Cu" "F.Mask" "F.Paste")
			(net "GND")
		)
		(pad "129" smd rect
			(at -2.050034 50.574956 270)
			(size 0.519938 1.4986)
			(layers "F.Cu" "F.Mask" "F.Paste")
			(net "M_H_CPU0_SB_DQ<20>")
		)
		(pad "130" smd rect
			(at -2.050034 51.425094 270)
			(size 0.519938 1.4986)
			(layers "F.Cu" "F.Mask" "F.Paste")
			(net "GND")
		)
		(pad "131" smd rect
			(at -2.050034 52.274978 270)
			(size 0.519938 1.4986)
			(layers "F.Cu" "F.Mask" "F.Paste")
			(net "M_H_CPU0_SB_DQ<21>")
		)
		(pad "132" smd rect
			(at -2.050034 53.125116 270)
			(size 0.519938 1.4986)
			(layers "F.Cu" "F.Mask" "F.Paste")
			(net "GND")
		)
		(pad "133" smd rect
			(at -2.050034 53.975 270)
			(size 0.519938 1.4986)
			(layers "F.Cu" "F.Mask" "F.Paste")
			(net "M_H_CPU0_SB_DQ<24>")
		)
		(pad "134" smd rect
			(at -2.050034 54.824884 270)
			(size 0.519938 1.4986)
			(layers "F.Cu" "F.Mask" "F.Paste")
			(net "GND")
		)
		(pad "135" smd rect
			(at -2.050034 55.675022 270)
			(size 0.519938 1.4986)
			(layers "F.Cu" "F.Mask" "F.Paste")
			(net "M_H_CPU0_SB_DQ<25>")
		)
		(pad "136" smd rect
			(at -2.050034 56.524906 270)
			(size 0.519938 1.4986)
			(layers "F.Cu" "F.Mask" "F.Paste")
			(net "GND")
		)
		(pad "137" smd rect
			(at -2.050034 57.375044 270)
			(size 0.519938 1.4986)
			(layers "F.Cu" "F.Mask" "F.Paste")
			(net "M_H_CPU0_SB_DQS_DP<3>")
		)
	)
)
